(kicad_pcb
	(version 20260206)
	(generator "pcbnew")
	(generator_version "10.0")
	(general
		(thickness 1.6)
		(legacy_teardrops no)
	)
	(paper "A4")
	(title_block
		(title "Bryce Canyon_F.DPB_16315-1-OCP.brd")
		(comment 1 "Bryce Canyon / footprints 42-44 of 2223")
	)
	(layers
		(0 "F.Cu" signal "TOP")
		(4 "In1.Cu" signal "L2GND")
		(6 "In2.Cu" signal "L3")
		(8 "In3.Cu" signal "L4GND")
		(10 "In4.Cu" signal "L5")
		(12 "In5.Cu" signal "L6VCC")
		(14 "In6.Cu" signal "L7VCC")
		(16 "In7.Cu" signal "L8")
		(18 "In8.Cu" signal "L9GND")
		(20 "In9.Cu" signal "L10")
		(22 "In10.Cu" signal "L11GND")
		(2 "B.Cu" signal "BOTTOM")
		(9 "F.Adhes" user "F.Adhesive")
		(11 "B.Adhes" user "B.Adhesive")
		(13 "F.Paste" user "Package Geometry/Pastemask Top")
		(15 "B.Paste" user "Package Geometry/Pastemask Bottom")
		(5 "F.SilkS" user "Ref Des/Silkscreen Top")
		(7 "B.SilkS" user "Ref Des/Silkscreen Bottom")
		(1 "F.Mask" user "Board Geometry/Soldermask Top")
		(3 "B.Mask" user "Board Geometry/Soldermask Bottom")
		(17 "Dwgs.User" user "User.Drawings")
		(19 "Cmts.User" user "User.Comments")
		(21 "Eco1.User" user "User.Eco1")
		(23 "Eco2.User" user "User.Eco2")
		(25 "Edge.Cuts" user "Board Geometry/Outline")
		(27 "Margin" user)
		(31 "F.CrtYd" user "Package Geometry/Place Bound Top")
		(29 "B.CrtYd" user "Package Geometry/Place Bound Bottom")
		(35 "F.Fab" user "Ref Des/Assembly Top")
		(33 "B.Fab" user "Ref Des/Assembly Bottom")
	)
	(footprint ""
		(layer "F.Cu")
		(at 451.749922 -172.909992 -90)
		(property "Reference" "HDDSAS22"
			(at 0 0 270)
			(layer "F.SilkS")
			(hide yes)
			(effects
				(font
					(size 1.27 1.27)
				)
			)
		)
		(property "Value" "SKT-SAS15P-14P-45-GP"
			(at -20.7645 -8.9789 270)
			(unlocked yes)
			(layer "F.Fab")
			(hide yes)
			(effects
				(font
					(size 1.016 1.016)
					(thickness 0.1524)
				)
			)
		)
		(property "Device Type" "10120818-001C-TRLF"
			(at -20.7645 -10.5029 270)
			(unlocked yes)
			(layer "F.Fab")
			(hide yes)
			(effects
				(font
					(size 1.016 1.016)
					(thickness 0.1524)
				)
			)
		)
		(duplicate_pad_numbers_are_jumpers no)
		(fp_line
			(start 1.651 4.2926)
			(end 1.651 3.0099)
			(stroke
				(width 0.1524)
				(type default)
			)
			(layer "F.SilkS")
		)
		(fp_line
			(start 8.509 4.2926)
			(end 1.651 4.2926)
			(stroke
				(width 0.1524)
				(type default)
			)
			(layer "F.SilkS")
		)
		(fp_line
			(start -23.4188 3.0099)
			(end -23.4188 -3.2512)
			(stroke
				(width 0.1524)
				(type default)
			)
			(layer "F.SilkS")
		)
		(fp_line
			(start 1.651 3.0099)
			(end -23.4188 3.0099)
			(stroke
				(width 0.1524)
				(type default)
			)
			(layer "F.SilkS")
		)
		(fp_line
			(start 8.509 3.0099)
			(end 8.509 4.2926)
			(stroke
				(width 0.1524)
				(type default)
			)
			(layer "F.SilkS")
		)
		(fp_line
			(start 23.4188 3.0099)
			(end 8.509 3.0099)
			(stroke
				(width 0.1524)
				(type default)
			)
			(layer "F.SilkS")
		)
		(fp_line
			(start -23.4188 -3.2512)
			(end 23.4188 -3.2512)
			(stroke
				(width 0.1524)
				(type default)
			)
			(layer "F.SilkS")
		)
		(fp_line
			(start 23.4188 -3.2512)
			(end 23.4188 3.0099)
			(stroke
				(width 0.1524)
				(type default)
			)
			(layer "F.SilkS")
		)
		(fp_line
			(start 15.5067 -3.3401)
			(end 16.2687 -3.3401)
			(stroke
				(width 0.3302)
				(type default)
			)
			(layer "F.SilkS")
		)
		(fp_poly
			(pts
				(xy 15.868904 -3.230372) (xy 16.503904 -3.865372) (xy 15.233904 -3.865372)
			)
			(stroke
				(width 0)
				(type default)
			)
			(fill yes)
			(layer "F.SilkS")
		)
		(fp_poly
			(pts
				(xy -22.8727 -2.7559) (xy 22.8727 -2.7559) (xy 22.8727 2.7559) (xy 8.255 2.7559) (xy 8.255 3.5179)
				(xy 1.905 3.5179) (xy 1.905 2.7559) (xy -22.8727 2.7559)
			)
			(stroke
				(width 0)
				(type default)
			)
			(fill no)
			(layer "F.CrtYd")
		)
		(fp_poly
			(pts
				(xy 1.397 4.5466) (xy 1.397 3.2639) (xy -23.6728 3.2639) (xy -23.6728 -3.5052) (xy 23.6728 -3.5052)
				(xy 23.6728 -0.00635) (xy 22.8727 -0.00635) (xy 22.8727 -2.7559) (xy -22.8727 -2.7559) (xy -22.8727 2.7559)
				(xy 1.905 2.7559) (xy 1.905 3.5179) (xy 8.255 3.5179) (xy 8.255 2.7559) (xy 22.8727 2.7559) (xy 22.8727 0.00635)
				(xy 23.6728 0.00635) (xy 23.6728 3.2639) (xy 8.763 3.2639) (xy 8.763 4.5466)
			)
			(stroke
				(width 0)
				(type default)
			)
			(fill no)
			(layer "F.CrtYd")
		)
		(fp_poly
			(pts
				(xy 1.397 4.5466) (xy 1.397 3.2639) (xy -23.6728 3.2639) (xy -23.6728 -3.5052) (xy 23.6728 -3.5052)
				(xy 23.6728 3.2639) (xy 8.763 3.2639) (xy 8.763 4.5466)
			)
			(stroke
				(width 0)
				(type default)
			)
			(fill no)
			(layer "F.Fab")
		)
		(pad "" np_thru_hole circle
			(at -18.874994 0 270)
			(size 0.254 0.254)
			(drill 1.3462)
			(layers "*.Cu" "*.Mask")
			(clearance 0.9017)
			(thermal_gap 0.9017)
		)
		(pad "" np_thru_hole circle
			(at 18.874994 0 270)
			(size 0.254 0.254)
			(drill 0.9398)
			(layers "*.Cu" "*.Mask")
			(clearance 0.6985)
			(thermal_gap 0.6985)
		)
		(pad "G1" smd rect
			(at 21.874988 0 270)
			(size 2.5908 2.5908)
			(layers "F.Cu" "F.Mask" "F.Paste")
			(net "GND")
		)
		(pad "G2" smd rect
			(at -21.874988 0 270)
			(size 2.5908 2.5908)
			(layers "F.Cu" "F.Mask" "F.Paste")
			(net "GND")
		)
		(pad "P1" smd rect
			(at 1.905 -1.82499 270)
			(size 0.6096 2.3622)
			(layers "F.Cu" "F.Mask" "F.Paste")
			(net "Net_2101")
		)
		(pad "P2" smd rect
			(at 0.635 -1.82499 270)
			(size 0.6096 2.3622)
			(layers "F.Cu" "F.Mask" "F.Paste")
			(net "Net_2102")
		)
		(pad "P3" smd rect
			(at -0.635 -1.82499 270)
			(size 0.6096 2.3622)
			(layers "F.Cu" "F.Mask" "F.Paste")
			(net "Net_2103")
		)
		(pad "P4" smd rect
			(at -1.905 -1.82499 270)
			(size 0.6096 2.3622)
			(layers "F.Cu" "F.Mask" "F.Paste")
			(net "GND")
		)
		(pad "P5" smd rect
			(at -3.175 -1.82499 270)
			(size 0.6096 2.3622)
			(layers "F.Cu" "F.Mask" "F.Paste")
			(net "HDD_PRSNT_22")
		)
		(pad "P6" smd rect
			(at -4.445 -1.82499 270)
			(size 0.6096 2.3622)
			(layers "F.Cu" "F.Mask" "F.Paste")
			(net "GND")
		)
		(pad "P7" smd rect
			(at -5.715 -1.82499 270)
			(size 0.6096 2.3622)
			(layers "F.Cu" "F.Mask" "F.Paste")
			(net "5V_PRE_22")
		)
		(pad "P8" smd rect
			(at -6.985 -1.82499 270)
			(size 0.6096 2.3622)
			(layers "F.Cu" "F.Mask" "F.Paste")
			(net "P5V_HDD22")
		)
		(pad "P9" smd rect
			(at -8.255 -1.82499 270)
			(size 0.6096 2.3622)
			(layers "F.Cu" "F.Mask" "F.Paste")
			(net "P5V_HDD22")
		)
		(pad "P10" smd rect
			(at -9.525 -1.82499 270)
			(size 0.6096 2.3622)
			(layers "F.Cu" "F.Mask" "F.Paste")
			(net "GND")
		)
		(pad "P11" smd rect
			(at -10.795 -1.82499 270)
			(size 0.6096 2.3622)
			(layers "F.Cu" "F.Mask" "F.Paste")
			(net "ACT_HDD_22")
		)
		(pad "P12" smd rect
			(at -12.065 -1.82499 270)
			(size 0.6096 2.3622)
			(layers "F.Cu" "F.Mask" "F.Paste")
			(net "GND")
		)
		(pad "P13" smd rect
			(at -13.335 -1.82499 270)
			(size 0.6096 2.3622)
			(layers "F.Cu" "F.Mask" "F.Paste")
			(net "12V_PRE_22")
		)
		(pad "P14" smd rect
			(at -14.605 -1.82499 270)
			(size 0.6096 2.3622)
			(layers "F.Cu" "F.Mask" "F.Paste")
			(net "P12V_HDD22")
		)
		(pad "P15" smd rect
			(at -15.875 -1.82499 270)
			(size 0.6096 2.3622)
			(layers "F.Cu" "F.Mask" "F.Paste")
			(net "P12V_HDD22")
		)
		(pad "S1" smd rect
			(at 15.875 -1.82499 270)
			(size 0.6096 2.3622)
			(layers "F.Cu" "F.Mask" "F.Paste")
			(net "GND")
		)
		(pad "S2" smd rect
			(at 14.605 -1.82499 270)
			(size 0.6096 2.3622)
			(layers "F.Cu" "F.Mask" "F.Paste")
			(net "SAS_HDD_RX_P22")
		)
		(pad "S3" smd rect
			(at 13.335 -1.82499 270)
			(size 0.6096 2.3622)
			(layers "F.Cu" "F.Mask" "F.Paste")
			(net "SAS_HDD_RX_N22")
		)
		(pad "S4" smd rect
			(at 12.065 -1.82499 270)
			(size 0.6096 2.3622)
			(layers "F.Cu" "F.Mask" "F.Paste")
			(net "GND")
		)
		(pad "S5" smd rect
			(at 10.795 -1.82499 270)
			(size 0.6096 2.3622)
			(layers "F.Cu" "F.Mask" "F.Paste")
			(net "PHY_DRV_A_TO_SCC_A_22_DN")
		)
		(pad "S6" smd rect
			(at 9.525 -1.82499 270)
			(size 0.6096 2.3622)
			(layers "F.Cu" "F.Mask" "F.Paste")
			(net "PHY_DRV_A_TO_SCC_A_22_DP")
		)
		(pad "S7" smd rect
			(at 8.255 -1.82499 270)
			(size 0.6096 2.3622)
			(layers "F.Cu" "F.Mask" "F.Paste")
			(net "GND")
		)
		(pad "S8" smd rect
			(at 7.480046 2.845054 270)
			(size 0.508 2.3622)
			(layers "F.Cu" "F.Mask" "F.Paste")
			(net "GND")
		)
		(pad "S9" smd rect
			(at 6.679946 2.845054 270)
			(size 0.508 2.3622)
			(layers "F.Cu" "F.Mask" "F.Paste")
			(net "Net_460")
		)
		(pad "S10" smd rect
			(at 5.8801 2.845054 270)
			(size 0.508 2.3622)
			(layers "F.Cu" "F.Mask" "F.Paste")
			(net "Net_352")
		)
		(pad "S11" smd rect
			(at 5.08 2.845054 270)
			(size 0.508 2.3622)
			(layers "F.Cu" "F.Mask" "F.Paste")
			(net "GND")
		)
		(pad "S12" smd rect
			(at 4.2799 2.845054 270)
			(size 0.508 2.3622)
			(layers "F.Cu" "F.Mask" "F.Paste")
			(net "Net_388")
		)
		(pad "S13" smd rect
			(at 3.480054 2.845054 270)
			(size 0.508 2.3622)
			(layers "F.Cu" "F.Mask" "F.Paste")
			(net "Net_424")
		)
		(pad "S14" smd rect
			(at 2.679954 2.845054 270)
			(size 0.508 2.3622)
			(layers "F.Cu" "F.Mask" "F.Paste")
			(net "GND")
		)
		(zone
			(layer "F.Cu")
			(hatch none 0.5)
			(connect_pads
				(clearance 0)
			)
			(min_thickness 0.25)
			(keepout
				(tracks not_allowed)
				(vias allowed)
				(pads allowed)
				(copperpour not_allowed)
				(footprints allowed)
			)
			(placement
				(enabled no)
				(sheetname "")
			)
			(fill
				(thermal_gap 0.5)
				(thermal_bridge_width 0.5)
				(island_removal_mode 0)
			)
			(polygon
				(pts
					(xy 455.407522 -189.648592) (xy 448.333622 -189.648592) (xy 448.333622 -196.582792) (xy 449.438522 -196.582792)
					(xy 449.438522 -192.467992) (xy 454.061322 -192.467992) (xy 454.061322 -196.582792) (xy 455.407522 -196.582792)
				)
			)
		)
		(zone
			(layer "F.Cu")
			(hatch none 0.5)
			(connect_pads
				(clearance 0)
			)
			(min_thickness 0.25)
			(keepout
				(tracks allowed)
				(vias not_allowed)
				(pads allowed)
				(copperpour not_allowed)
				(footprints allowed)
			)
			(placement
				(enabled no)
				(sheetname "")
			)
			(fill
				(thermal_gap 0.5)
				(thermal_bridge_width 0.5)
				(island_removal_mode 0)
			)
			(polygon
				(pts
					(xy 455.407522 -189.648592) (xy 448.333622 -189.648592) (xy 448.333622 -196.582792) (xy 449.438522 -196.582792)
					(xy 449.438522 -192.467992) (xy 454.061322 -192.467992) (xy 454.061322 -196.582792) (xy 455.407522 -196.582792)
				)
			)
		)
		(zone
			(layer "F.Cu")
			(hatch none 0.5)
			(connect_pads
				(clearance 0)
			)
			(min_thickness 0.25)
			(keepout
				(tracks allowed)
				(vias not_allowed)
				(pads allowed)
				(copperpour not_allowed)
				(footprints allowed)
			)
			(placement
				(enabled no)
				(sheetname "")
			)
			(fill
				(thermal_gap 0.5)
				(thermal_bridge_width 0.5)
				(island_removal_mode 0)
			)
			(polygon
				(pts
					(xy 455.407522 -156.171392) (xy 448.333622 -156.171392) (xy 448.333622 -149.237192) (xy 449.438522 -149.237192)
					(xy 449.438522 -153.351992) (xy 454.061322 -153.351992) (xy 454.061322 -149.237192) (xy 455.407522 -149.237192)
				)
			)
		)
		(zone
			(layer "F.Cu")
			(hatch none 0.5)
			(connect_pads
				(clearance 0)
			)
			(min_thickness 0.25)
			(keepout
				(tracks not_allowed)
				(vias allowed)
				(pads allowed)
				(copperpour not_allowed)
				(footprints allowed)
			)
			(placement
				(enabled no)
				(sheetname "")
			)
			(fill
				(thermal_gap 0.5)
				(thermal_bridge_width 0.5)
				(island_removal_mode 0)
			)
			(polygon
				(pts
					(xy 455.407522 -156.171392) (xy 448.333622 -156.171392) (xy 448.333622 -149.237192) (xy 449.438522 -149.237192)
					(xy 449.438522 -153.351992) (xy 454.061322 -153.351992) (xy 454.061322 -149.237192) (xy 455.407522 -149.237192)
				)
			)
		)
		(zone
			(layers "F.Cu" "B.Cu" "In1.Cu" "In2.Cu" "In3.Cu" "In4.Cu" "In5.Cu" "In6.Cu"
				"In7.Cu" "In8.Cu" "In9.Cu" "In10.Cu"
			)
			(hatch none 0.5)
			(connect_pads
				(clearance 0)
			)
			(min_thickness 0.25)
			(keepout
				(tracks not_allowed)
				(vias allowed)
				(pads allowed)
				(copperpour not_allowed)
				(footprints allowed)
			)
			(placement
				(enabled no)
				(sheetname "")
			)
			(fill
				(thermal_gap 0.5)
				(thermal_bridge_width 0.5)
				(island_removal_mode 0)
			)
			(polygon
				(pts
					(arc
						(start 452.524622 -154.034998)
						(mid 450.975222 -154.034998)
						(end 452.524622 -154.034998)
					)
				)
			)
		)
		(zone
			(layers "F.Cu" "B.Cu" "In1.Cu" "In2.Cu" "In3.Cu" "In4.Cu" "In5.Cu" "In6.Cu"
				"In7.Cu" "In8.Cu" "In9.Cu" "In10.Cu"
			)
			(hatch none 0.5)
			(connect_pads
				(clearance 0)
			)
			(min_thickness 0.25)
			(keepout
				(tracks not_allowed)
				(vias allowed)
				(pads allowed)
				(copperpour not_allowed)
				(footprints allowed)
			)
			(placement
				(enabled no)
				(sheetname "")
			)
			(fill
				(thermal_gap 0.5)
				(thermal_bridge_width 0.5)
				(island_removal_mode 0)
			)
			(polygon
				(pts
					(arc
						(start 452.727822 -191.784986)
						(mid 450.772022 -191.784986)
						(end 452.727822 -191.784986)
					)
				)
			)
		)
	)
	(footprint ""
		(layer "F.Cu")
		(at 255.778 -295.783)
		(property "Reference" "U1"
			(at 0 0 0)
			(layer "F.SilkS")
			(hide yes)
			(effects
				(font
					(size 1.27 1.27)
				)
			)
		)
		(property "Value" "24LC64-I-SN-GP"
			(at -3.707384 -1.5367 0)
			(unlocked yes)
			(layer "F.Fab")
			(hide yes)
			(effects
				(font
					(size 1.016 1.016)
					(thickness 0.1524)
				)
			)
		)
		(property "Device Type" "SOIC8H69"
			(at -3.707384 -3.0607 0)
			(unlocked yes)
			(layer "F.Fab")
			(hide yes)
			(effects
				(font
					(size 1.016 1.016)
					(thickness 0.1524)
				)
			)
		)
		(duplicate_pad_numbers_are_jumpers no)
		(fp_line
			(start -2.7432 -1.4224)
			(end -2.7432 1.4224)
			(stroke
				(width 0.1524)
				(type default)
			)
			(layer "F.SilkS")
		)
		(fp_line
			(start -2.7432 1.4224)
			(end -2.6416 1.4224)
			(stroke
				(width 0.1524)
				(type default)
			)
			(layer "F.SilkS")
		)
		(fp_line
			(start -2.7432 1.4224)
			(end 2.1336 1.4224)
			(stroke
				(width 0.1524)
				(type default)
			)
			(layer "F.SilkS")
		)
		(fp_line
			(start -2.7178 -0.508)
			(end -2.1844 -0.0508)
			(stroke
				(width 0.1524)
				(type default)
			)
			(layer "F.SilkS")
		)
		(fp_line
			(start -2.6289 3.4417)
			(end -2.6289 1.4732)
			(stroke
				(width 0.381)
				(type default)
			)
			(layer "F.SilkS")
		)
		(fp_line
			(start -2.1844 -0.0508)
			(end -2.7178 0.508)
			(stroke
				(width 0.1524)
				(type default)
			)
			(layer "F.SilkS")
		)
		(fp_line
			(start 2.1336 -1.4224)
			(end -2.7432 -1.4224)
			(stroke
				(width 0.1524)
				(type default)
			)
			(layer "F.SilkS")
		)
		(fp_line
			(start 2.1336 1.4224)
			(end 2.1336 -1.4224)
			(stroke
				(width 0.1524)
				(type default)
			)
			(layer "F.SilkS")
		)
		(fp_poly
			(pts
				(xy -2.2098 -1.4224) (xy -2.2098 1.4224) (xy 2.2098 1.4224) (xy 2.2098 -1.4224)
			)
			(stroke
				(width 0)
				(type default)
			)
			(fill yes)
			(layer "F.SilkS")
		)
		(fp_rect
			(start -2.450084 2.999994)
			(end 2.450084 -2.999994)
			(stroke
				(width 0)
				(type default)
			)
			(fill no)
			(layer "F.CrtYd")
		)
		(fp_poly
			(pts
				(xy -2.8194 3.6322) (xy -2.8194 -3.6322) (xy 2.8194 -3.6322) (xy 2.8194 1.18364) (xy 2.450084 1.18364)
				(xy 2.450084 -2.999994) (xy -2.450084 -2.999994) (xy -2.450084 2.999994) (xy 2.450084 2.999994)
				(xy 2.450084 1.18618) (xy 2.8194 1.18618) (xy 2.8194 3.6322)
			)
			(stroke
				(width 0)
				(type default)
			)
			(fill no)
			(layer "F.CrtYd")
		)
		(fp_rect
			(start -2.8194 3.6322)
			(end 2.8194 -3.6322)
			(stroke
				(width 0)
				(type default)
			)
			(fill no)
			(layer "F.Fab")
		)
		(pad "1" smd rect
			(at -1.905 2.54)
			(size 0.635 1.651)
			(layers "F.Cu" "F.Mask" "F.Paste")
			(net "EEPROM_A0")
		)
		(pad "2" smd rect
			(at -0.635 2.54)
			(size 0.635 1.651)
			(layers "F.Cu" "F.Mask" "F.Paste")
			(net "EEPROM_A1")
		)
		(pad "3" smd rect
			(at 0.635 2.54)
			(size 0.635 1.651)
			(layers "F.Cu" "F.Mask" "F.Paste")
			(net "EEPROM_A2")
		)
		(pad "4" smd rect
			(at 1.905 2.54)
			(size 0.635 1.651)
			(layers "F.Cu" "F.Mask" "F.Paste")
			(net "GND")
		)
		(pad "5" smd rect
			(at 1.905 -2.54)
			(size 0.635 1.651)
			(layers "F.Cu" "F.Mask" "F.Paste")
			(net "EEPROM_SDA")
		)
		(pad "6" smd rect
			(at 0.635 -2.54)
			(size 0.635 1.651)
			(layers "F.Cu" "F.Mask" "F.Paste")
			(net "EEPROM_SCL")
		)
		(pad "7" smd rect
			(at -0.635 -2.54)
			(size 0.635 1.651)
			(layers "F.Cu" "F.Mask" "F.Paste")
			(net "EEPROM_WP")
		)
		(pad "8" smd rect
			(at -1.905 -2.54)
			(size 0.635 1.651)
			(layers "F.Cu" "F.Mask" "F.Paste")
			(net "P3V3_STBY_A")
		)
	)
	(footprint ""
		(layer "F.Cu")
		(at 329.819 -181.842918 180)
		(property "Reference" "C274"
			(at 0 0 180)
			(layer "F.SilkS")
			(hide yes)
			(effects
				(font
					(size 1.27 1.27)
				)
			)
		)
		(property "Value" "SC1U16V3KX-5GP"
			(at 0 -2.8194 180)
			(unlocked yes)
			(layer "F.Fab")
			(hide yes)
			(effects
				(font
					(size 1.016 1.016)
					(thickness 0.1524)
				)
			)
		)
		(property "Device Type" "C603H36"
			(at 0 -4.3434 180)
			(unlocked yes)
			(layer "F.Fab")
			(hide yes)
			(effects
				(font
					(size 1.016 1.016)
					(thickness 0.1524)
				)
			)
		)
		(duplicate_pad_numbers_are_jumpers no)
		(fp_line
			(start 0.508 0)
			(end -0.508 0)
			(stroke
				(width 0.2032)
				(type default)
			)
			(layer "F.SilkS")
		)
		(fp_rect
			(start -0.5842 1.3335)
			(end 0.5842 -1.3335)
			(stroke
				(width 0)
				(type default)
			)
			(fill no)
			(layer "F.CrtYd")
		)
		(fp_rect
			(start -0.5842 1.3335)
			(end 0.5842 -1.3335)
			(stroke
				(width 0)
				(type default)
			)
			(fill no)
			(layer "F.Fab")
		)
		(pad "1" smd custom
			(at 0 -0.762 180)
			(size 0.2159 0.2159)
			(layers "F.Cu" "F.Mask" "F.Paste")
			(net "P5V_HDD18")
			(options
				(clearance outline)
				(anchor circle)
			)
			(primitives
				(gr_poly
					(pts
						(arc
							(start -0.3302 -0.4318)
							(mid -0.402042 -0.402042)
							(end -0.4318 -0.3302)
						)
						(arc
							(start -0.4318 0.3302)
							(mid -0.402042 0.402042)
							(end -0.3302 0.4318)
						)
						(arc
							(start 0.3302 0.4318)
							(mid 0.402042 0.402042)
							(end 0.4318 0.3302)
						)
						(arc
							(start 0.4318 -0.3302)
							(mid 0.402042 -0.402042)
							(end 0.3302 -0.4318)
						)
					)
					(width 0)
					(fill yes)
				)
			)
		)
		(pad "2" smd custom
			(at 0 0.762 180)
			(size 0.2159 0.2159)
			(layers "F.Cu" "F.Mask" "F.Paste")
			(net "GND")
			(options
				(clearance outline)
				(anchor circle)
			)
			(primitives
				(gr_poly
					(pts
						(arc
							(start -0.3302 -0.4318)
							(mid -0.402042 -0.402042)
							(end -0.4318 -0.3302)
						)
						(arc
							(start -0.4318 0.3302)
							(mid -0.402042 0.402042)
							(end -0.3302 0.4318)
						)
						(arc
							(start 0.3302 0.4318)
							(mid 0.402042 0.402042)
							(end 0.4318 0.3302)
						)
						(arc
							(start 0.4318 -0.3302)
							(mid 0.402042 -0.402042)
							(end 0.3302 -0.4318)
						)
					)
					(width 0)
					(fill yes)
				)
			)
		)
	)
)
